1
1
2
2
3
3
4
4
5
5
6
6
D D
C C
B B
A A
timingcard.com
1SHEET OF 7
Cannot open file 
C:\Users\<user>\Desktop\Ti
mecard 
Logo\TIMECARD.jpg. 
File does not exist.
REV DATEP3 09/14/21
1
2
3
GND4 VCC8
7
6
5
U8
NC7WV125K8X
GND
1
2
3
J1
1909763-1
5
1
234
AN1
RF2-49B-T-00-50-G-HDW
GND
R25
49.9RANT1_OUT
+3.3V
+3.3V
ANT1_IN
GNDGND
+3.3V
1234
D1
8240136
1
2
3
GND4 VCC8
7
6
5
U11
NC7WV125K8X
GND
1
2
3
J3
1909763-1
5
1
234
AN3
RF2-49B-T-00-50-G-HDW
GND
R28
49.9RANT3_OUT
+3.3V+3.3V
ANT3_IN
GNDGND
+3.3V
1
2
3
GND4 VCC8
7
6
5
U16
NC7WV125K8X
1
2
3
J4
1909763-1
5
1
234
AN4
RF2-49B-T-00-50-G-HDW
GND
R34
49.9RANT4_OUT
+3.3V+3.3V
ANT4_IN
GNDGND
+3.3V
1
2
3
GND4 VCC8
7
6
5
U12
NC7WV125K8X
GND
1
2
3
J2
1909763-1
5
1
234
AN2
RF2-49B-T-00-50-G-HDW
GND
R33
49.9RANT2_OUT
+3.3V+3.3V
ANT2_IN
GNDGND
+3.3V
1234
D2
8240136
+3.3V
GND
+3.3V
GND
INPUT/OUTPUT SIGNALS
ANT1_IO_OUT
ANT1_IO_IN
ANT2_IO_OUT
ANT2_IO_IN
ANT3_IO_OUT
ANT3_IO_IN
ANT4_IO_OUT
ANT4_IO_IN
GND
R144.7K_1%_0402R154.7K_1%_0402R294.7K_1%_0402R304.7K_1%_0402
R174.7K_1%_0402R164.7K_1%_0402R314.7K_1%_0402R324.7K_1%_040212C280.1uF_25V_0402
12C290.1uF_25V_040212C260.1uF_25V_0402
12C270.1uF_25V_0402



1
1
2
2
3
3
4
4
5
5
6
6
D D
C C
B B
A A
Title
Number RevisionSize
B
Date: 8/28/2023 Sheet   of
File: C:\Users\<user>\02-USER_IO_STATUS.SchDocDrawn By:
+3.3V+3.3V+3.3V+3.3V
LED1 LED2 LED3 LED4
SYSTEM STATUS LEDS
R35
200 OHM
R36
200 OHM
R38
200 OHM
R39
200 OHM
ANODE 1
B2 G3 R4
D13
155124M173200
ANODE 1
B2 G3 R4
D14
155124M173200
ANODE 1
B2 G3 R4
D15
155124M173200
ANODE 1
B2 G3 R4
D16
155124M173200
ANODE 1
B2 G3 R4
D17
155124M173200
ANODE 1
B2 G3 R4
D18
155124M173200
SDB1
AD2
VCC3
GND4
ISET5
SDA6
SCL7 OUT1 8
OUT2 9
OUT3 10
GND11
OUT4 12
OUT5 13
OUT6 14
OUT7 15
OUT8 16
OUT9 17
GND18
OUT10 19
OUT11 20
OUT12 21
OUT13 22
OUT14 23
OUT15 24
GND25 OUT16 26
OUT17 27
OUT18 28EP29
U6
IS32FL3207
+3.3V
IO STATUS LEDS
GNSS 1
GNSS 2
IO 1
IO 2
IO 3
IO 4
C40
0.1uF
C38
1uF
R40
DNI_100k
GNDGND GNDGND
+3.3V
+3.3V
LED DRIVER (0x6E)
SENS_I2C_SDA
SENS_I2C_SCL
R41
4.7K
GND
R109
4.7K_0402
+3.3V
R110DNI_4.7K_0402
GND
R108
4.7K_0402
21D3L TST -C191KGKT21D9L TST -C191KGKT21D10L TST -C191KGKT21D11L TST -C191KGKT



1
1
2
2
3
3
4
4
5
5
6
6
D D
C C
B B
A A
timingcard.com
*SHEET OF *
Cannot open file 
C:\Users\<user>\Desktop\Ti
mecard 
Logo\TIMECARD.jpg. 
File does not exist.
REV DATEP3 09/14/21
+12V
GND
+3.3V
GND
10uF
C1
SF-0603S500-2
5.00A
SF-0603S500-2CT-ND
F1
C2
0.1uF
GND
+12V_PCIE
R44
DNI_0_5%_1206
1
2
1
2
J38A
39-30-0040
3
4
3
4
J38B
39-30-0040
VIN+8
VIN-7
A0 2
A1 1
SCL 4
SDA 3VS5
GND 6
U2
INA219BIDR
R7
2mOhm_1%_1206
+12V_SENS
12C2010uF_16V_0603
+3.3V
GND GND
+12V_SENS+12V
GND
SENS_I2C_SCL
SENS_I2C_SDA
R62 0_1%_0402
R64 0_1%_0402
Address 0x40
+12V
12C114.7uF_50V_120612C124.7uF_50V_120612+C10100uF_16V_2917
P5V_SENSE
R8
2mOhm_1%_1206
12C1510uF_16V_060312+C14100uF_16V_291712C162.2uF_16V_040212C171uF_16V_040212C180.1uF_25V_040212C1347uF_16V_1206
GND
VIN+8
VIN-7
A0 2
A1 1
SCL 4
SDA 3VS5
GND 6
U17
INA219BIDR
12C2210uF_16V_0603
+3.3V
GND GND
P5V_SENSE
GND
SENS_I2C_SCL
SENS_I2C_SDA
R65 0_1%_0402
R66 0_1%_0402
Address 0x41 +3.3V
+12V
12C764.7uF_50V_120612C774.7uF_50V_120612+C75100uF_16V_2917
P3V3_SENSE
R72
2mOhm_1%_1206
12C8010uF_16V_060312+C79100uF_16V_291712C812.2uF_16V_040212C821uF_16V_040212C830.1uF_25V_040212C7847uF_16V_1206
GND
VIN+8
VIN-7
A0 2
A1 1
SCL 4
SDA 3VS5
GND 6
U19
INA219BIDR
12C8510uF_16V_0603
+3.3V
GND GND
P3V3_SENSE
GND
SENS_I2C_SCL
SENS_I2C_SDA
R79 0_1%_0402
R80 0_1%_0402
Address 0x44 +3.3V
+3.3VGND
+5.0V
+5.0V
+5.0V
+3.3V
12
R77
200_1%_0402
12
R1
200_1%_0402
21
D23
SMDJ12A
GND
21D20LTST-C191KGKT21D4LTST-C191KGKT
GND
GND
Vin1
Vin2 Vout 6
Vout 7
ON/OFF12
PWGOOD11
Sense 5
Trim 4
GND 3
GND 8
GND 9
GND 10
GND 13
GND 14
GND(Thermal Pad)23
GND(Thermal Pad)15
GND(Thermal Pad)16
GND(Thermal Pad)17
GND(Thermal Pad)18
GND(Thermal Pad)19
GND(Thermal Pad)20
GND(Thermal Pad)21
GND(Thermal Pad)22
U18
DNI_MYMGK00506ERSR
VIN1
PHASE2
PHASE3
PHASE4
GND5
GND6
GND7
EN8
PGOOD9
VOUT10
VOUT11
VOUT12
VOUT 13VOUT 14ILIM 15FB 16VCC 17BST 18VIN 19VIN 20VIN_TPD 21PHASE_TPD22GND_TPD23VOUT_TPD24GND_TPD25
U24
MUN12AD06-SM
P3V3_SENSE+12V
+12V
GND
12+C4470uF_10V_2917
R61
2.2K_0.5%_040212
R63
22_0.5%_0402
Vin1
Vin2 Vout 6
Vout 7
ON/OFF12
PWGOOD11
Sense 5
Trim 4
GND 3
GND 8
GND 9
GND 10
GND 13
GND 14
GND(Thermal Pad)23
GND(Thermal Pad)15
GND(Thermal Pad)16
GND(Thermal Pad)17
GND(Thermal Pad)18
GND(Thermal Pad)19
GND(Thermal Pad)20
GND(Thermal Pad)21
GND(Thermal Pad)22
U5
DNI_MYMGK00506ERSR
P5V_SENSE+12V
+12V
GND
R26
1.2K_0.5%_040212
R27
160_0.5%_0402
Two power supply options
+12V
GND
P3V3_MUN_PHASE
P3V3_MUN_PHASE
+12V
GND
P3V3_SENSE
P3V3_SENSE
P3V3_SENSE
R69 0_1%_0402
R70
4.7K_1%_0402
+12V
P3V3_MUN_VCC
P3V3_MUN_VCC
12C52.2uF_16V_0402
GND
1 2R67
88.7K_0.5%_0402
R68
2K_0.5%_0402P3V3_SENSE
GND
P3V3_MUN_FB
P3V3_MUN_FB
VIN1
PHASE2
PHASE3
PHASE4
GND5
GND6
GND7
EN8
PGOOD9
VOUT10
VOUT11
VOUT12
VOUT 13VOUT 14ILIM 15FB 16VCC 17BST 18VIN 19VIN 20VIN_TPD 21PHASE_TPD22GND_TPD23VOUT_TPD24GND_TPD25
U1
MUN12AD06-SM
+12V
GND
P5V_MUN_PHASE
P5V_MUN_PHASE
+12V
GND
P5V_SENSE
P5V_SENSE
P5V_SENSE
R4 0_1%_0402
R5
4.7K_1%_0402
+12V
P5V_MUN_VCC
P5V_MUN_VCC
12C32.2uF_16V_0402
GND
P5V_SENSE
GND
P5V_MUN_FB
P5V_MUN_FB
1 2
3
CR1
MBRD10200CT-13
12+C71470uF_10V_2917
12+C7247uF_35V_291712+C7347uF_35V_2917
R3 0_1%_0402R2
147K_1%_0402
C210.1uF_25V_0402
C190.1uF_25V_0402C660.1uF_25V_0402
R18510K_1%_0402
R12920K_1%_0402
GND
R18320K_1%_0402
R18410K_1%_0402
R6 20K_1%_0402
R9 20K_1%_0402
R6010K_1%_0402
GND
R5910K_1%_0402



1
1
2
2
3
3
4
4
5
5
6
6
D D
C C
B B
A A
timingcard.com
*SHEET OF *
Cannot open file 
C:\Users\<user>\Desktop\Ti
mecard 
Logo\TIMECARD.jpg. 
File does not exist.
REV DATEP3 09/14/21
GND GND
+12V_PCIE+3.3V_PCIE
+3.3V
+3.3V_PCIE
+12V_PCIE
PCIE_RX0_P
PCIE_RX0_N
PCIE_RX1_P
PCIE_RX1_N
PCIE_RX2_P
PCIE_RX2_N
PCIE_RX3_P
PCIE_RX3_N
PCIE_PERST
PCIE_CLK_P
PCIE_CLK_N
PCIE_TX0_P
PCIE_TX0_N
PCIE_TX1_P
PCIE_TX1_N
PCIE_TX2_P
PCIE_TX2_N
PCIE_TX3_P
PCIE_TX3_N
PCIe Connector
4.7K
R22
0.1UFC53
0.1UFC52
0 OHM
R24
0 OHM
R23
0.1UFC51
0.1UFC49
0.1UFC47
0.1UFC45
0.1UFC44
0.1UFC46
0.1UFC48
0.1UFC50
KEY KEY
+12v1B1
+12V2B2
+12V3B3
GND1B4
SMCLKB5
SMDATAB6
GND2B7
+3.3V1B8
JTAG/TRST_nB9
+3.3vauxB10
WAKE_nB11
RESERVED1B12
GND3B13
PETp0B14
PETn0B15
GND4B16
PRSNT2_nB17
GND5B18
PETp1B19
PETn1B20
GND6B21
GND7B22
PETp2B23
PETn2B24
GND8B25
GND9B26
PETp3B27
PETn3B28
GND10B29
RESERVED2B30
PRSNT4_nB31
GND11B32
PRSNT1_nA1
+12V5 A2
+12V4 A3
GND37 A4
JTAG/TCKA5
JTAG/TDIA6
JTAG/TDOA7
JTAG/TMSA8
+3.3V3 A9
+3.3V2 A10
PERST A11
GND36 A12
REFCLK+A13
REFCLK- A14
GND35 A15
PERp0 A16
PERn0 A17
GND34 A18
RESERVED5A19
GND33 A20
PERp1 A21
PERn1 A22
GND32 A23
GND31 A24
PERp2 A25
PERn2 A26
GND30 A27
GND29 A28
PERp3 A29
PERn3 A30
GND28 A31
RESERVED4A32
P2
PCIex4
GND
+3.3V
GND GND GND GND+3.3V +3.3V +3.3V +3.3V
FPGA_TCK
FPGA_TDO
FPGA_TMS
FPGA_TDI
JTAG
33 OHM
R18
33 OHM
R19
33 OHM
R20
33 OHM
R21
BAT54SW
231
D8
BAT54SW
231
D7
BAT54SW
231
D6
BAT54SW
231
D5
PRSNT
PRSNT
PRSNT
FPGA_TCK FPGA_TDO FPGA_TMS FPGA_TDI
3
21
4
5 6
7 8
9 10
P4
TSM-105-01-L-DV



1
1
2
2
3
3
4
4
5
5
6
6
D D
C C
B B
A A
timingcard.com
*SHEET OF *
Cannot open file 
C:\Users\<user>\Desktop\Ti
mecard 
Logo\TIMECARD.jpg. 
File does not exist.
REV DATEP3 09/14/21
+5.0V
GND
+3.3V
GND GND
RCB_GPS1_TP2
RCB_GPS1_TP1
RCB_GPS1_RX
RCB_GPS1_TX
GPS1_RST
GPS
VCC_ANT1
VCC2
TXD3
RST4 RXD 5TP1 6TP2 7GND 8
U9
RCB-F9T VCC4 SCL 1
SDA 3
WP5 GND 2
U7
AT24MAC402-STUM-T
SDA
SCL
+3.3V
GND
C59
0.1uF
C61
0.1uF
C25
0.1uF
+3.3V
GND
EXT_EEPROM_WP
R37
10K
EEPROM
VDD8
VDDIO6
CS 2
SCK 4
SDI 3
SDO 5
GND 1
GND 7
U14
BME280
GNDGND
C31
0.1uF
C30
0.1uF
+3.3V+3.3V
SENS_I2C_SCL
SENS_I2C_SDA
+3.3V
GND GND
ENVIRONMENT (0x76)
IMU (0x29) , BNO080 alternative allowed
GND
GND GND
RCB_GPS2_TP2
RCB_GPS2_TP1
RCB_GPS2_RX
RCB_GPS2_TX
GPS2_RST
VCC_ANT1
VCC2
TXD3
RST4 RXD 5TP1 6TP2 7GND 8
U15
RCB-F9T-1
C36
0.1uF
C37
0.1uF
12
C58
10uF
12
C60
10uF
12
C34
10uF
12
C35
10uF
1
2
3
4
5
6
7
8
9
10
11
12
P3
EXT GPIO
+3.3V
GNDGND
+3.3V
EXT_GPIO_1
EXT_GPIO_2
EXT_GPIO_3
EXT_GPIO_4
EXT_GPIO_7
EXT_GPIO_8
EXT_GPIO_9
EXT_GPIO_10
EXTERNAL GPIO
36-24393-ND
J5
GNSS Standoff
36-24393-ND
J7
GNSS Standoff
36-24393-ND
J8
GNSS Standoff
36-24393-ND
J9
GNSS Standoff
36-24393-ND
J10
GNSS Standoff
36-24393-ND
J11
GNSS Standoff
36-24393-ND
J12
GNSS Standoff
36-24393-ND
J14
GNSS Standoff
335-1156-ND
J15
M3 screw
335-1156-ND
J16
M3 screw
335-1156-ND
J17
M3 screw
335-1156-ND
J18
M3 screw
335-1156-ND
J19
M3 screw
335-1156-ND
J20
M3 screw
335-1156-ND
J21
M3 screw
335-1156-ND
J22
M3 screw
335-1156-ND
J23
M3 screw
335-1156-ND
J24
M3 screw
335-1156-ND
J25
M3 screw
335-1156-ND
J26
M3 screw
335-1156-ND
J27
M3 screw
335-1156-ND
J28
M3 screw
335-1156-ND
J29
M3 screw
335-1156-ND
J30
M3 screw
335-1156-ND
J32
M3 screw
335-1156-ND
J33
M3 screw
PCIe Bracket screws
1
2
3
4
5
P1
TSW-105-05-L-S
+3.3V
GND
ANADC_I2C_SCL
ANADC_I2C_SDA
MAC_FREQ_CTRLR48 DNI_0_1%_0402
Allow DAC daughter card to control atomic clock analog input
11
22
33
44
5 5
6 6
7 7
8 8
99
1010
1111
1212
13 13
14 14
15 15
16 16
SAM11878-ND
J6
GNSS Header 16-pin
11
22
33
44
5 5
6 6
7 7
8 8
99
1010
1111
1212
13 13
14 14
15 15
16 16
SAM11878-ND
J13
GNSS Header 16-pin
GND GND
C57
0.1uF
C64
0.1uF
12
C55
10uF
12
C56
10uF
GND
GND
+5.0V+3.3V
GND GND
C43
0.1uF
C54
0.1uF
12
C41
10uF
12
C42
10uF
RCB_GPS1_PIN11
RCB_GPS1_PIN12
GPS1_PIN13
GPS1_PIN14
GPS1_PIN15
RCB_GPS2_PIN11
RCB_GPS2_PIN12
GPS2_PIN13
GPS2_PIN14
GPS2_PIN15
VDD3
VDDIO28
NC1
SWDIO7
SWCLK8 BL IND 10
NC12
NC13
NC 15
NC 16
NC 21NC 22
NC23
NC24
PS06
PS15
BOOT LOAD PIN4
RESET11
CAP 9
INT 14
XIN3227 XOUT32 26
COM0 20
COM1 19
COM2 18
COM3 17
GND 2
GNDIO 25
U13
BNO055
GND
BNO_P3V3 BNO_P3V3
GND GND
BNO_P3V3
GNDGND
SENS_I2C_SCL
SENS_I2C_SDA
BNO_P3V3
PCIE_PERST R54 0_1%_0402
BNO_INT
BNO_INT
BNO_BLIND
BNO_XIN32
BNO_XOUT32
BNO_XIN32 BNO_XOUT32
R574.7K_0402R584.7K_0402R534.7K_0402R56DNI_4.7K_0402
R52
4.7K_0402
R50
4.7K_0402
R51
4.7K_0402
R55
4.7K_0402
1 2
C65
1uF_0402
2
1
3
4
P5
61300411121
+3.3V
DC_I2C_SCL
DC_I2C_SDA
GND
12
Y1
ABS07-32.768KHZ-T
C68
22pF_50V_0402
C39
22pF_50V_0402
GND GND
R73 DNI_0_1%_0402 FPGA_BNO_XOUT32
EN4 FB 2
IN6
NC 5
OUT 1
GND 3
GND 7
U25
NCP176AMX330TCG
R71
DNI_0_1%_0402FPGA_BNO_XIN32
BNO_P3V3
GND
12C810uF_16V_060312C92.2uF_16V_040212C321uF_16V_040212C330.1uF_25V_0402
+5.0V12C610uF_16V_060312C72.2uF_16V_0402
GND
C670.1uF_25V_0402C840.1uF_25V_0402
GNSS2_P3V3
GNSS2_P3V3
GNSS2_P5V0
GNSS2_P5V0
R186
10K_1%_0402



1
1
2
2
3
3
4
4
5
5
6
6
D D
C C
B B
A A
timingcard.com
*SHEET OF *
Cannot open file 
C:\Users\<user>\Desktop\Ti
mecard 
Logo\TIMECARD.jpg. 
File does not exist.
REV DATEP3 09/14/21
MAC_TX
MAC_RX
MAC_BITEMAC_RF_OUT
MAC_FREQ_CTRL
FPGA_MAC_PPS_DIFF_IN0
MAC_USB+
MAC_USB-
MAC_USB_PWR
MAC_PPS_OUT+
MAC_PPS_OUT-
MAC_ALARM
GND
GND
GND
MAC
10uF
C62
FREQ CTRL INP1
GND (CASE)P2
RF OUTP3
GND (SUPPLY & SIGNAL)P4 VCC P5BITE P6RS-232 TXP7RS-232 RXP8
RV-3049-C3
PPS-IN P9
PPS-OUT P10
U10A
RV-3049-C3
PPS-IN 1+1 USB DATA +2
PPS-IN 1-3 USB DATA -4
PPS-IN 0+5 USB POWER6
PPS-IN 0-7
GND 8
GND 9
NC10
NC11
NC12
NC13
NC14
GND 15NC16
PPS-OUT +17
NC18
PPS-OUT -19
ALARM 20
U10B
C63
0.1uF
DI12
DI23
DO+1 7
DO+2 6
DO-1 8
DO-2 5
GND 4VCC1
U3
DS90LV027AQMA
RIN1-1 RIN1+2
RIN2+3
RIN2-4
GND 5
ROUT2 6
ROUT1 7
VCC8
U4
DS90LV028AQMA
R11
4.7K
R10
4.7K C23
0.1uF
GNDGNDGND
+3.3V
MAC_PPS_IN1-
MAC_PPS_IN1+
MAC_PPS_IN0-
MAC_PPS_IN0+
GND
MAC_PPS_IN1-
MAC_PPS_IN1+
MAC_PPS_IN0-
MAC_PPS_IN0+
R12
110R
C24
0.1uF
+3.3V
GND GND
FPGA_MAC_PPSDIFF_OUT
MAC_PPS_OUT+
MAC_PPS_OUT-
FPGA_MAC_PPS_IN1-
MAC_PPS_IN
MAC_PPS_OUT
11
33
55
77
1010
1111
1212
1313
1414
1616
1818
WM24007CT-ND
2 2
4 4
6 6
17 17
19 19
20 20
8 8
9 9
15 15
J31
SA53_Header
GND
R45
0_5%_1206
R46
DNI_0_5%_1206
+5.0V +12V
12V and 3.3V Option for different Atomic clocks
MAC_VCC
R47
DNI_0_5%_1206
+3.3V
1
SKT2
0332-0-43-80-18-27-10-0
1
SKT5
0332-0-43-80-18-27-10-0
1
SKT6
0332-0-43-80-18-27-10-0
1
SKT9
0332-0-43-80-18-27-10-0
1
SKT1
0332-0-43-80-18-27-10-0
1
SKT3
0332-0-43-80-18-27-10-0
1
SKT4
0332-0-43-80-18-27-10-0
1
SKT7
0332-0-43-80-18-27-10-01
SKT8
0332-0-43-80-18-27-10-0
1
SKT10
0332-0-43-80-18-27-10-0
H700-ND
J39
SA53 Screw
H700-ND
J41
SA53 Screw
H700-ND
J40
SA53 Screw
H700-ND
J42
SA53 Screw



1
1
2
2
3
3
4
4
5
5
6
6
D D
C C
B B
A A
timingcard.com
*SHEET OF *
Cannot open file 
C:\Users\<user>\Desktop\Ti
mecard 
Logo\TIMECARD.jpg. 
File does not exist.
REV DATEP3 09/14/21
+5.0V
GND
KEY2
LED4
LED3
LED2
LED1
+5.0V
GND
GPS1_RST
GPS1_TP1
GPS1_TP2
GND
GPS1_RX
MAC_ALARM
MAC_BITE
FPGA_MAC_PPS_IN0-
FPGA_MAC_PPS_IN1-
FPGA_MAC_PPS_OUT-
MAC_RF_OUT
SDA
SCL
GND
GPS1_TX
MAC_FPGA_UART_RX
FPGA_MAC_UART_TX
MAC_USB+
MAC_USB-
MAC_USB_PWR
GND
PCIE_PERST
KEY1
FPGA_TCK
FPGA_TDO
GND
FPGA_TDI
FPGA_TMS
GND
PCIE_TX3_P
PCIE_TX3_N
PCIE_RX3_P
PCIE_RX3_N
PCIE_TX0_P
PCIE_TX0_N
PCIE_RX0_P
PCIE_RX0_N
GND
PCIE_TX2_P
PCIE_TX2_N
PCIE_RX2_P
PCIE_RX2_N
PCIE_TX1_P
PCIE_TX1_N
PCIE_RX1_P
PCIE_RX1_N
PCIE_CLK_P
PCIE_CLK_N
UART1_TXD
UART1_RXD
IO_LED1
IO_LED2
IO_LED3
IO_LED4
GPS2_RX_FPGAGPS2_TX_FPGA
GPS2_TP2
GPS2_TP1
GPS2_RST
ANT1_IO_OUT
ANT1_IO_IN
ANT2_IO_OUT
ANT2_IO_IN
ANT3_IO_OUT
ANT3_IO_IN
ANT4_IO_OUT
ANT4_IO_IN
EXT_GPIO_7
EXT_GPIO_8
EXT_GPIO_9
EXT_GPIO_10
EXT_GPIO_1
EXT_GPIO_2
EXT_GPIO_3
EXT_GPIO_4
ANT1_OUT
ANT1_IN
ANT2_OUT
ANT2_IN
ANT3_OUT
ANT3_IN
ANT4_OUT
ANT4_IN
EXT_EEPROM_WP
AXK680347YG
11 2 2
33 4 4
55 6 6
77 8 8
99 10 10
1111 12 12
1313 14 14
1515 16 16
1717 18 18
1919 20 20
2121 22 22
2323 24 24
2525 26 26
2727 28 28
2929 30 30
3131 32 32
3333 34 34
3535 36 36
3737 38 38
3939 40 40
4141 42 42
4343 44 44
4545 46 46
4747 48 48
4949 50 50
5151 52 52
5353 54 54
5555 56 56
5757 58 58
5959 60 60
6161 62 62
6363 64 64
6565 66 66
6767 68 68
6969 70 70
7171 72 72
7373 74 74
7575 76 76
7777 78 78
7979 80 80
8181 82 82
8383 84 84
J34
Single FPGA Conn
AXK680347YG
11 2 2
33 4 4
55 6 6
77 8 8
99 10 10
1111 12 12
1313 14 14
1515 16 16
1717 18 18
1919 20 20
2121 22 22
2323 24 24
2525 26 26
2727 28 28
2929 30 30
3131 32 32
3333 34 34
3535 36 36
3737 38 38
3939 40 40
4141 42 42
4343 44 44
4545 46 46
4747 48 48
4949 50 50
5151 52 52
5353 54 54
5555 56 56
5757 58 58
5959 60 60
6161 62 62
6363 64 64
6565 66 66
6767 68 68
6969 70 70
7171 72 72
7373 74 74
7575 76 76
7777 78 78
7979 80 80
8181 82 82
8383 84 84
J36
Single FPGA Conn
AXK680347YG
11 2 2
33 4 4
55 6 6
77 8 8
99 10 10
1111 12 12
1313 14 14
1515 16 16
1717 18 18
1919 20 20
2121 22 22
2323 24 24
2525 26 26
2727 28 28
2929 30 30
3131 32 32
3333 34 34
3535 36 36
3737 38 38
3939 40 40
4141 42 42
4343 44 44
4545 46 46
4747 48 48
4949 50 50
5151 52 52
5353 54 54
5555 56 56
5757 58 58
5959 60 60
6161 62 62
6363 64 64
6565 66 66
6767 68 68
6969 70 70
7171 72 72
7373 74 74
7575 76 76
7777 78 78
7979 80 80
8181 82 82
8383 84 84
J35
Single FPGA Conn
AXK680347YG
11 2 2
33 4 4
55 6 6
77 8 8
99 10 10
1111 12 12
1313 14 14
1515 16 16
1717 18 18
1919 20 20
2121 22 22
2323 24 24
2525 26 26
2727 28 28
2929 30 30
3131 32 32
3333 34 34
3535 36 36
3737 38 38
3939 40 40
4141 42 42
4343 44 44
4545 46 46
4747 48 48
4949 50 50
5151 52 52
5353 54 54
5555 56 56
5757 58 58
5959 60 60
6161 62 62
6363 64 64
6565 66 66
6767 68 68
6969 70 70
7171 72 72
7373 74 74
7575 76 76
7777 78 78
7979 80 80
8181 82 82
8383 84 84
J37
Single FPGA Conn
GPS1_PIN15
GPS1_PIN14
GPS1_PIN12
GPS1_PIN13
GPS1_PIN11
GPS2_PIN15
GPS2_PIN13
GPS2_PIN11 GPS2_PIN12
GPS2_PIN14
BNO_INT
FPGA_BNO_XIN32
FPGA_BNO_XOUT32



1
1
2
2
3
3
4
4
5
5
6
6
D D
C C
B B
A A
Title
Number RevisionSize
B
Date: 8/28/2023 Sheet   of
File: C:\Users\<user>\08-DIPSwitches_I2C.SchDoc Drawn By:
DIP Switch, Configure UART and PPS Single ended versus differential
GND
DIP_SW_UART_SEL
DIP_SW_PPS_SEL
UART either goes to FPGA or to GPS2
R7810K_1%_0402
+3.3V
R8810K_1%_0402
UART_SEL = 0 for FTDI <-> GPS2, 1 for FTDI <-> FPGA and FPGA <-> GPS2
PPS_SEL = 0 for Single Ended PPS, 1 for Differential PPS (SA53)
R8910K_1%_0402
DIP_SW_MACSER_SEL
DIP_SW_PPS_SEL
Status LEDs
PPS_SEL = 0 for Single Ended PPS, 1 for Differential PPS (SA53)
UART_SEL = 0 for FTDI <-> GPS2, 1 for FTDI <-> FPGA and FPGA <-> GPS2
21
D22
LTST-C191KGKT
R122
200_1%_0402
+3.3V
DIP_SW_UART_SEL 21
D21
LTST-C191KGKT
R112
200_1%_0402
+3.3V
DIP_SW_MACSER_SEL 21
D24
LTST-C191KGKT
R125
200_1%_0402
+3.3V
MACSER = 0 for I2C to MAC, 1 for UART to MAC
VCC9
SEL11
SEL25
NO12
NO24
COM1 11
COM2 7
FLT12
OE6
NC110
NC28
GND 3
U26
TMUX1072RUTR
GND
12C690.1uF_25V_0402
+3.3V
GND
Connect UART to MAC otherwise
DIP_SW_MACSER_SEL
GND
R76 27_1%_0402
R95 27_1%_0402
R111 27_1%_0402
R94 27_1%_0402
R74 DNI_27_1%_0402
R75 DNI_27_1%_0402
MAC_I2C_SCL
MAC_I2C_SDA
MAC_TX
MAC_RX
MAC_FPGA_UART_RX
FPGA_MAC_UART_TX
FPGA_MAC_UART_TX
MAC_FPGA_UART_RX
RESET1
SD0 2
SC0 3
SD1 4
SC1 5
GND 6
SD2 7
SC2 8
SD3 9
SC3 10
A211
SCL12 SDA13
VCC14
A015 A116
EP 17
U27
PCA9546ARGVR
I2C MUX address 7'0x70
R12627_1%_0402R12727_1%_0402R12827_1%_0402
GND
12C700.1uF_25V_0402
+3.3V
GNDPCIE_PERST R12127_1%_0402
SCL
SDA
GND
MAC_I2C_SCL
MAC_I2C_SDA
R1234.7K_1%_0402R1244.7K_1%_0402
+3.3V
R1134.7K_1%_0402R1144.7K_1%_0402R1154.7K_1%_0402R1164.7K_1%_0402R1174.7K_1%_0402R1184.7K_1%_0402R1194.7K_1%_0402R1204.7K_1%_0402
+3.3V
ANADC_I2C_SCL
ANADC_I2C_SDA
DC_I2C_SCL
DC_I2C_SDA
SENS_I2C_SCL
SENS_I2C_SDA
1 8SW1A
1571983-4
2 7SW1B
1571983-4
3 6SW1C
1571983-4
4 5SW1D
1571983-4
R14010K_1%_0402
DIP_SW_GPS2_SEL1 4
2 3
SW2
219-2LPST DIP_SW_GPS1_SEL
R14110K_1%_0402
DIP_SW_GPS2_SEL
GPS2_SEL = 0 for RCB, 1 for M2
21
D12
LTST-C191KGKT
R178
200_1%_0402
+3.3V
DIP_SW_GPS1_SEL 21
D19
LTST-C191KGKT
R179
200_1%_0402
+3.3V
GPS1_SEL = 0 for RCB, 1 for M2



1
1
2
2
3
3
4
4
5
5
6
6
D D
C C
B B
A A
Title
Number RevisionSize
B
Date: 8/28/2023 Sheet   of
File: C:\Users\<user>\09-USBUart_PPSMUX_UARTMUX.SchDocDrawn By:
3V3OUT3
VCC4
VCCIO9
CTS 11
RESET2
RTS 8
CBUS0 6
RXD 10TXD 7
USBDM1
USBDP12
GND 5
GND 13
U20
FT234XD-R
12C8610nF_50V_0402
1 2FB1
600ohm_1.3A_0603
GND
FTDI_USB_R_N
FTDI_USB_R_P
12C920.1uF_25V_0402
R81 27_1%_0402
R43 27_1%_0402FTDI_USB_N
FTDI_USB_P
FTDI_VBUSUSB_VBUS
GND
GND
R82
10K_1%_0402
GND
12C9110nF_50V_0402
R13 27_1%_0402
R42 27_1%_0402 FTDI_TX
FTDI_RX
12C890.1uF_25V_040212C904.7uF_16V_040212C930.1uF_25V_0402
USB to UART
VCC9
SEL11
SEL25
NO12
NO24
COM1 11
COM2 7
FLT12
OE6
NC110
NC28
GND 3
U22
TMUX1072RUTR
GND
12C950.1uF_25V_0402
GNSS2_P3V3
GND
Select GPS Uart, either FTDI or FPGA
DIP_SW_UART_SEL
GND
R90 27_1%_0402
R92 27_1%_0402
GPS2_RX_FPGA
GPS2_TX_FPGA
FTDI_TX
FTDI_RX
GPS2_RX
GPS2_TX
R93 27_1%_0402
R91 27_1%_0402
VCC9
SEL11
SEL25
NO12
NO24
COM1 11
COM2 7
FLT12
OE6
NC110
NC28
GND 3
U21
TMUX1072RUTR
GND
12C940.1uF_25V_0402
+3.3V
GND
Connect FTDI to FPGA otherwise
DIP_SW_UART_SEL
GND
R84 27_1%_0402
R86 27_1%_0402
R87 27_1%_0402
R85 27_1%_0402
UART1_TXD
UART1_RXD
GND
GND
FTDI_TX
FTDI_RX
VCC9
SEL11
SEL25
NO12
NO24
COM1 11
COM2 7
FLT12
OE6
NC110
NC28
GND 3
U23
TMUX1072RUTR
GND
12C960.1uF_25V_0402
+3.3V
GND
Atomic clock PPS input / output select
DIP_SW_PPS_SEL
GND
MAC_PPS_OUTSingle ended PPS output R96 49.9_1%_0402 FPGA_MAC_PPS_OUT -FPGA Single ended PPS Input
FPGA_MAC_PPSDIFF_OUTR97 49.9_1%_0402Diff PPS Output
MAC_PPS_IN R98 49.9_1%_0402
R99 49.9_1%_0402
Single ended PPS input
FPGA_MAC_PPS_DIFF_IN0
Single ended to diff PPS input
FPGA_MAC_PPS_IN0- FPGA Single ended PPS Output
R102DNI_27_1%_0402
R103DNI_27_1%_0402GPS2_RX_FPGA
GPS2_TX_FPGA
R100DNI_27_1%_0402
R101DNI_27_1%_0402
FTDI_RX
FTDI_TX
R107 DNI_49.9_1%_0402
R105 DNI_49.9_1%_0402
R104 DNI_49.9_1%_0402 MAC_PPS_OUT
R106 DNI_49.9_1%_0402 FPGA_MAC_PPSDIFF_OUT
MAC_PPS_IN
FPGA_MAC_PPS_DIFF_IN0
12R8315K_1%_0402C8747pF_50V_0402C8847pF_50V_0402
VBUS 1
D- 2
D+ 3
ID 4
GND 5
SHLD1 6
SHLD2 7
SHLD3 8
SHLD4 9
SHLD6 11SHLD5 10
J43
47589-0001
EN4 FB 2
IN6
NC 5
OUT 1
GND 3
GND 7
U33
NCP176AMX330TCG
12C1150.1uF_25V_0402
FTDI_VBUS
FTDI_VBUS
GND
12C1141uF_16V_0402
GND
12C1120.1uF_25V_040212C1111uF_16V_0402
GND
FTDI_P3V3
VIN13
VIN26
MODE5
PR14
VOUT 2
VOUT 7
ST 8
GND 1
U32
TPS2116DRLR
FTDI_P3V3+3.3V
R49
10K_5%_0402
R181
10K_5%_0402
GND
GND
12C1100.1uF_25V_0402
GNSS2_P3V3
VIN13
VIN26
MODE5
PR14
VOUT 2
VOUT 7
ST 8
GND 1
U34
TPS2116DRLR
R180
10K_5%_0402
R182
10K_5%_0402
GND
GND
12C1130.1uF_25V_0402
GNSS2_P5V0FTDI_VBUS+5.0V



1
1
2
2
3
3
4
4
5
5
6
6
D D
C C
B B
A A
Title
Number RevisionSize
B
Date: 8/28/2023 Sheet   of
File: C:\Users\<user>\10-M2_GPS.SchDoc Drawn By:
GND
+3.3V
GND
GPS1_RST
Socket 2 Key B PCIe-based WWAN Adapter Pinout , table 3-21 in M.2 spec
M2_GPS1_TP2
M2_GPS1_TP1
M2_GPS1_RX
M2_GPS1_TX
GPS1_RST
GPS1_PIN13
GPS1_PIN14
GPS1_PIN15
M2_GPS1_PIN11
M2_GPS1_PIN12
1
3
5
7
9
11
21
23
25
27
29
31
33
35
37
39
41
43
45
47
49
51
53
55
57
59
61
63
65
67
69
71
73
75
MNT 2
1
3
5
7
9
11
21
23
25
27
29
31
33
35
37
39
41
43
45
47
49
51
53
55
57
59
61
63
65
67
69
71
73
75
77
J44A
2199119-3
2
4
6
8
10
20
22
24
26
28
30
32
34
36
38
40
42
44
46
48
50
52
54
56
58
60
62
64
66
68
70
72
74
MNT 1
2
4
6
8
10
20
22
24
26
28
30
32
34
36
38
40
42
44
46
48
50
52
54
56
58
60
62
64
66
68
70
72
74
76
J44B
2199119-3
10MHz to module
1PPS to Module
R130 DNI_0_1%_0402
1PPS out here on some cards
R138 0_1%_0402 M2_GPS1_TP1
I2C & IRQ
R1324.7K_1%_0402R1334.7K_1%_0402R1344.7K_1%_0402
GND
GND
GPS2_RST
M2_GPS2_TP2
M2_GPS2_TP1
M2_GPS2_RX
M2_GPS2_TX
GPS2_RST
GPS2_PIN13
GPS2_PIN14
GPS2_PIN15
M2_GPS2_PIN11
M2_GPS2_PIN12
1
3
5
7
9
11
21
23
25
27
29
31
33
35
37
39
41
43
45
47
49
51
53
55
57
59
61
63
65
67
69
71
73
75
MNT 2
1
3
5
7
9
11
21
23
25
27
29
31
33
35
37
39
41
43
45
47
49
51
53
55
57
59
61
63
65
67
69
71
73
75
77
J45A
2199119-3
2
4
6
8
10
20
22
24
26
28
30
32
34
36
38
40
42
44
46
48
50
52
54
56
58
60
62
64
66
68
70
72
74
MNT 1
2
4
6
8
10
20
22
24
26
28
30
32
34
36
38
40
42
44
46
48
50
52
54
56
58
60
62
64
66
68
70
72
74
76
J45B
2199119-3
10MHz to module
1PPS to Module
R131 DNI_0_1%_0402
1PPS out here on some cards
R139 0_1%_0402 M2_GPS2_TP1
I2C & IRQ
R1354.7K_1%_0402R1364.7K_1%_0402R1374.7K_1%_0402
12C740.1uF_25V_040212C970.1uF_25V_040212C980.1uF_25V_040212C990.1uF_25V_040212C1000.1uF_25V_040212C1010.1uF_25V_040212C1020.1uF_25V_040212C1030.1uF_25V_040212C1040.1uF_25V_040212C1050.1uF_25V_0402
GNSS2_P3V3



1
1
2
2
3
3
4
4
5
5
6
6
D D
C C
B B
A A
Title
Number RevisionSize
B
Date: 8/28/2023 Sheet   of
File: C:\Users\<user>\11-M2_RCB_MUX.SchDoc Drawn By:
NC11
A02
NO23
NC25
GND6
NO37
A110
COM2 4COM3 8NC3 9NO4 11COM4 12NC4 13VCC 14NO1 15COM1 1617 17
U29
PI3A412ZHE
GNSS modules need to MUX 6 signals, use 1x4 channel MUX and 1x2 channel MUX
12
C107
0.1uF_25V_0402
+3.3V
GND
DIP_SW_GPS1_SEL
GND
R152 49.9_1%_0402
R150 49.9_1%_0402
R147 49.9_1%_0402
R144 49.9_1%_0402
RCB_GPS1_TP2
RCB_GPS1_TP1
RCB_GPS1_RX
RCB_GPS1_TX
RCB_GPS1_PIN11
RCB_GPS1_PIN12
R155DNI_27_1%_0402
R157DNI_27_1%_0402
R161DNI_27_1%_0402
R159DNI_27_1%_0402
RST is just tied to both, and I2C and IRQ is tied to both
VCC9
SEL11
SEL25
NO12
NO24
COM1 11
COM2 7
FLT12
OE6
NC110
NC28
GND 3
U31
TMUX1072RUTR
GND
12C1090.1uF_25V_0402
+3.3V
GND
DIP_SW_GPS1_SEL
GND
R174 DNI_49.9_1%_0402
R172 DNI_49.9_1%_0402
R170 DNI_49.9_1%_0402
R173 DNI_49.9_1%_0402
R176 49.9_1%_0402
R177 49.9_1%_0402
R162DNI_27_1%_0402
R163DNI_27_1%_0402
R165DNI_27_1%_0402
R164DNI_27_1%_0402
GPS1_TX
M2_GPS1_TP2
M2_GPS1_TP1
M2_GPS1_RX
M2_GPS1_TX
GPS1_PIN11
GPS1_PIN12
M2_GPS1_PIN11
M2_GPS1_PIN12
RCB_GPS1_PIN11
M2_GPS1_PIN11
RCB_GPS1_PIN12
M2_GPS1_PIN12
RCB_GPS1_TX
M2_GPS1_TX
GPS1_RX
GPS1_TP1
GPS1_TP2
RCB_GPS1_RX
RCB_GPS1_TP1
RCB_GPS1_TP2
M2_GPS1_RX
M2_GPS1_TP1
M2_GPS1_TP2
NC11
A02
NO23
NC25
GND6
NO37
A110
COM2 4COM3 8NC3 9NO4 11COM4 12NC4 13VCC 14NO1 15COM1 1617 17
U28
PI3A412ZHE
12
C106
0.1uF_25V_0402
+3.3V
GND
DIP_SW_GPS2_SEL
GND
R146 49.9_1%_0402
R145 49.9_1%_0402
R143 49.9_1%_0402
R142 49.9_1%_0402
RCB_GPS2_TP2
RCB_GPS2_TP1
RCB_GPS2_RX
RCB_GPS2_TX
RCB_GPS2_PIN11
RCB_GPS2_PIN12
R148DNI_27_1%_0402
R149DNI_27_1%_0402
R153DNI_27_1%_0402
R151DNI_27_1%_0402
VCC9
SEL11
SEL25
NO12
NO24
COM1 11
COM2 7
FLT12
OE6
NC110
NC28
GND 3
U30
TMUX1072RUTR
GND
12C1080.1uF_25V_0402
+3.3V
GND
DIP_SW_GPS2_SEL
GND
R169 DNI_49.9_1%_0402
R167 DNI_49.9_1%_0402
R166 DNI_49.9_1%_0402
R168 DNI_49.9_1%_0402
R171 49.9_1%_0402
R175 49.9_1%_0402
R154DNI_27_1%_0402
R156DNI_27_1%_0402
R160DNI_27_1%_0402
R158DNI_27_1%_0402
GPS2_TX
M2_GPS2_TP2
M2_GPS2_TP1
M2_GPS2_RX
M2_GPS2_TX
GPS2_PIN11
GPS2_PIN12
M2_GPS2_PIN11
M2_GPS2_PIN12
RCB_GPS2_PIN11
M2_GPS2_PIN11
RCB_GPS2_PIN12
M2_GPS2_PIN12
RCB_GPS2_TX
M2_GPS2_TX
GPS2_RX
GPS2_TP1
GPS2_TP2
RCB_GPS2_RX
RCB_GPS2_TP1
RCB_GPS2_TP2
M2_GPS2_RX
M2_GPS2_TP1
M2_GPS2_TP2
A = 0, NC <-> COM, A=1, NO <-> COM
A = 0, NC <-> COM, A=1, NO <-> COM
SEL = LL, NC <-> COM , SEL = HH, NO <-> COM
SEL = LL, NC <-> COM , SEL = HH, NO <-> COM